# S9S_MB_2U (Grand Teton) — schematic netlist excerpt (pin names and nets, part order shuffled) for the footprints in the layout excerpt that follows; sources: Cadence DE-HDL packaged netlist, KiCad conversion of 03242023_DA0F0TMBIJ0_F0T_Motherboard_J_brd_V01_OCP.brd

J23  SCONN288_ADR50017P130CC  SCONN288_ADR50017-P130CC IO  pkg DDR288S_1-1VXB  page 104
  VIN_BULK0  = P12V_S3_AUX_CPU1_NVDIMM
  RFU0  = TP_CHD_CPU1_DIMM1_FRU_0
  VIN_MGMT  = P3V3_AUX
  HSCL  = I3C_SPD_DDRABCD_CPU1_LVC1_SCL_6
  HSDA  = I3C_SPD_DDRABCD_CPU1_LVC1_SDA
  VSS0  = GND
  DQ0_A  = M_D_CPU1_SA_DQ<0>
  VSS1  = GND
  DQ1_A  = M_D_CPU1_SA_DQ<1>
  VSS2  = GND
  DQS0_A_T  = M_D_CPU1_SA_DQS_DP<0>
  DQS0_A_C  = M_D_CPU1_SA_DQS_DN<0>
  VSS3  = GND
  DQ4_A  = M_D_CPU1_SA_DQ<4>
  VSS4  = GND
  DQ5_A  = M_D_CPU1_SA_DQ<5>
  VSS5  = GND
  DQ8_A  = M_D_CPU1_SA_DQ<8>
  VSS6  = GND
  DQ9_A  = M_D_CPU1_SA_DQ<9>
  VSS7  = GND
  DQS1_A_T  = M_D_CPU1_SA_DQS_DP<1>
  DQS1_A_C  = M_D_CPU1_SA_DQS_DN<1>
  VSS8  = GND
  DQ12_A  = M_D_CPU1_SA_DQ<12>
  VSS9  = GND
  DQ13_A  = M_D_CPU1_SA_DQ<13>
  VSS10  = GND
  DQ16_A  = M_D_CPU1_SA_DQ<16>
  VSS11  = GND
  DQ17_A  = M_D_CPU1_SA_DQ<17>
  VSS12  = GND
  DQS2_A_T  = M_D_CPU1_SA_DQS_DP<2>
  DQS2_A_C  = M_D_CPU1_SA_DQS_DN<2>
  VSS13  = GND
  DQ20_A  = M_D_CPU1_SA_DQ<20>
  VSS14  = GND
  DQ21_A  = M_D_CPU1_SA_DQ<21>
  VSS15  = GND
  DQ24_A  = M_D_CPU1_SA_DQ<24>
  VSS16  = GND
  DQ25_A  = M_D_CPU1_SA_DQ<25>
  VSS17  = GND
  DQS3_A_T  = M_D_CPU1_SA_DQS_DP<3>
  DQS3_A_C  = M_D_CPU1_SA_DQS_DN<3>
  VSS18  = GND
  DQ28_A  = M_D_CPU1_SA_DQ<28>
  VSS19  = GND
  DQ29_A  = M_D_CPU1_SA_DQ<29>
  VSS20  = GND
  CB0_A  = M_D_CPU1_SA_CB<0>
  VSS21  = GND
  CB1_A  = M_D_CPU1_SA_CB<1>
  VSS22  = GND
  DQS4_A_T  = M_D_CPU1_SA_DQS_DP<4>
  DQS4_A_C  = M_D_CPU1_SA_DQS_DN<4>
  VSS23  = GND
  CB4_A  = M_D_CPU1_SA_CB<4>
  VSS24  = GND
  CB5_A  = M_D_CPU1_SA_CB<5>
  VSS25  = GND
  ALERT_N  = M_D_CPU1_ALERT_N
  VSS26  = GND
  CS0_A_N  = M_D_CPU1_SA_CS_N<0>
  VSS27  = GND
  CA0_A  = M_D_CPU1_SA_CA<0>
  VSS28  = GND
  CA2_A  = M_D_CPU1_SA_CA<2>
  VSS29  = GND
  CA4_A  = M_D_CPU1_SA_CA<4>
  VSS30  = GND
  CA6_A  = M_D_CPU1_SA_CA<6>
  VSS31  = GND
  PAR_A  = M_D_CPU1_SA_PAR
  VSS32  = GND
  CA0_B  = M_D_CPU1_SB_CA<0>
  VSS33  = GND
  CA2_B  = M_D_CPU1_SB_CA<2>
  VSS34  = GND
  CA4_B  = M_D_CPU1_SB_CA<4>
  VSS35  = GND
  CA6_B  = M_D_CPU1_SB_CA<6>
  VSS36  = GND
  CS0_B_N  = M_D_CPU1_SB_CS_N<0>
  VSS37  = GND
  \lbd||rsp_a_n\  = M_D_CPU1_SA_RSP<0>
  \lbs||rsp_b_n\  = M_D_CPU1_SB_RSP<0>
  VSS38  = GND
  CB4_B  = M_D_CPU1_SB_CB<4>
  VSS39  = GND
  CB5_B  = M_D_CPU1_SB_CB<5>
  VSS40  = GND
  \dqs9_b_t||tdqs9_b_t||dbi4_b_n\  = M_D_CPU1_SB_DQS_DP<9>
  \dqs9_b_c||tdqs9_b_c\  = M_D_CPU1_SB_DQS_DN<9>
  VSS41  = GND
  CB0_B  = M_D_CPU1_SB_CB<0>
  VSS42  = GND
  CB1_B  = M_D_CPU1_SB_CB<1>
  VSS43  = GND
  DQ0_B  = M_D_CPU1_SB_DQ<0>
  VSS44  = GND
  DQ1_B  = M_D_CPU1_SB_DQ<1>
  VSS45  = GND
  DQS0_B_T  = M_D_CPU1_SB_DQS_DP<0>
  DQS0_B_C  = M_D_CPU1_SB_DQS_DN<0>
  VSS46  = GND
  DQ4_B  = M_D_CPU1_SB_DQ<4>
  VSS47  = GND
  DQ5_B  = M_D_CPU1_SB_DQ<5>
  VSS48  = GND
  DQ8_B  = M_D_CPU1_SB_DQ<8>
  VSS49  = GND
  DQ9_B  = M_D_CPU1_SB_DQ<9>
  VSS50  = GND
  DQS1_B_T  = M_D_CPU1_SB_DQS_DP<1>
  DQS1_B_C  = M_D_CPU1_SB_DQS_DN<1>
  VSS51  = GND
  DQ12_B  = M_D_CPU1_SB_DQ<12>
  VSS52  = GND
  DQ13_B  = M_D_CPU1_SB_DQ<13>
  VSS53  = GND
  DQ16_B  = M_D_CPU1_SB_DQ<16>
  VSS54  = GND
  DQ17_B  = M_D_CPU1_SB_DQ<17>
  VSS55  = GND
  DQS2_B_T  = M_D_CPU1_SB_DQS_DP<2>
  DQS2_B_C  = M_D_CPU1_SB_DQS_DN<2>
  VSS56  = GND
  DQ20_B  = M_D_CPU1_SB_DQ<20>
  VSS57  = GND
  DQ21_B  = M_D_CPU1_SB_DQ<21>
  VSS58  = GND
  DQ24_B  = M_D_CPU1_SB_DQ<24>
  VSS59  = GND
  DQ25_B  = M_D_CPU1_SB_DQ<25>
  VSS60  = GND
  DQS3_B_T  = M_D_CPU1_SB_DQS_DP<3>
  DQS3_B_C  = M_D_CPU1_SB_DQS_DN<3>
  VSS61  = GND
  DQ28_B  = M_D_CPU1_SB_DQ<28>
  VSS62  = GND
  DQ29_B  = M_D_CPU1_SB_DQ<29>
  VSS63  = GND
  RFU1  = TP_CHD_CPU1_DIMM1_FRU_1
  VIN_BULK1  = P12V_S3_AUX_CPU1_NVDIMM
  VIN_BULK2  = P12V_S3_AUX_CPU1_NVDIMM
  \pwr_good||fail_n\  = PWRGD_CHD_CPU1_DIMM1
  HSA  = PD_CHD_CPU1_DIMM1_SAA
  RFU2  = TP_CHD_CPU1_DIMM1_FRU_2
  RFU3  = TP_CHD_CPU1_DIMM1_FRU_3
  VSS64  = GND
  DQ2_A  = M_D_CPU1_SA_DQ<2>
  VSS65  = GND
  DQ3_A  = M_D_CPU1_SA_DQ<3>
  VSS66  = GND
  \dqs5_a_c||tdqs5_a_c||dqs5_a_t||tdqs5_a_t\  = M_D_CPU1_SA_DQS_DN<5>
  \dqs5_a_t||tdqs5_a_t\  = M_D_CPU1_SA_DQS_DP<5>
  VSS67  = GND
  DQ6_A  = M_D_CPU1_SA_DQ<6>
  VSS68  = GND
  DQ7_A  = M_D_CPU1_SA_DQ<7>
  VSS69  = GND
  DQ10_A  = M_D_CPU1_SA_DQ<10>
  VSS70  = GND
  DQ11_A  = M_D_CPU1_SA_DQ<11>
  VSS71  = GND
  \dqs6_a_c||tdqs6_a_c||dqs6_a_t||tdqs6_a_t\  = M_D_CPU1_SA_DQS_DN<6>
  \dqs6_a_t||tdqs6_a_t\  = M_D_CPU1_SA_DQS_DP<6>
  VSS72  = GND
  DQ14_A  = M_D_CPU1_SA_DQ<14>
  VSS73  = GND
  DQ15_A  = M_D_CPU1_SA_DQ<15>
  VSS74  = GND
  DQ18_A  = M_D_CPU1_SA_DQ<18>
  VSS75  = GND
  DQ19_A  = M_D_CPU1_SA_DQ<19>
  VSS76  = GND
  \dqs7_a_c||tdqs7_a_c\  = M_D_CPU1_SA_DQS_DN<7>
  \dqs7_a_t||tdqs7_a_t\  = M_D_CPU1_SA_DQS_DP<7>
  VSS77  = GND
  DQ22_A  = M_D_CPU1_SA_DQ<22>
  VSS78  = GND
  DQ23_A  = M_D_CPU1_SA_DQ<23>
  VSS79  = GND
  DQ26_A  = M_D_CPU1_SA_DQ<26>
  VSS80  = GND
  DQ27_A  = M_D_CPU1_SA_DQ<27>
  VSS81  = GND
  \dqs8_a_c||tdqs8_a_c\  = M_D_CPU1_SA_DQS_DN<8>
  \dqs8_a_t||tdqs8_a_t\  = M_D_CPU1_SA_DQS_DP<8>
  VSS82  = GND
  DQ30_A  = M_D_CPU1_SA_DQ<30>
  VSS83  = GND
  DQ31_A  = M_D_CPU1_SA_DQ<31>
  VSS84  = GND
  CB2_A  = M_D_CPU1_SA_CB<2>
  VSS85  = GND
  CB3_A  = M_D_CPU1_SA_CB<3>
  VSS86  = GND
  \dqs9_a_c||tdqs9_a_c\  = M_D_CPU1_SA_DQS_DN<9>
  \dqs9_a_t||tdqs9_a_t\  = M_D_CPU1_SA_DQS_DP<9>
  VSS87  = GND
  CB6_A  = M_D_CPU1_SA_CB<6>
  VSS88  = GND
  CB7_A  = M_D_CPU1_SA_CB<7>
  VSS89  = GND
  RESET_N  = RST_M_CD_CPU1_FPGA_N
  VSS90  = GND
  CS1_A_N  = M_D_CPU1_SA_CS_N<1>
  VSS91  = GND
  CA1_A  = M_D_CPU1_SA_CA<1>
  VSS92  = GND
  CA3_A  = M_D_CPU1_SA_CA<3>
  VSS93  = GND
  CA5_A  = M_D_CPU1_SA_CA<5>
  VSS94  = GND
  CK_T  = M_D_CPU1_CLK_DP<0>
  CK_C  = M_D_CPU1_CLK_DN<0>
  VSS95  = GND
  RFU4  = TP_CHD_CPU1_DIMM1_FRU_4
  CA1_B  = M_D_CPU1_SB_CA<1>
  VSS96  = GND
  CA3_B  = M_D_CPU1_SB_CA<3>
  VSS97  = GND
  CA5_B  = M_D_CPU1_SB_CA<5>
  VSS98  = GND
  PAR_B  = M_D_CPU1_SB_PAR
  VSS99  = GND
  CS1_B_N  = M_D_CPU1_SB_CS_N<1>
  VSS100  = GND
  RFU5  = TP_CHD_CPU1_DIMM1_FRU_5
  RFU6  = TP_CHD_CPU1_DIMM1_FRU_6
  VSS101  = GND
  CB6_B  = M_D_CPU1_SB_CB<6>
  VSS102  = GND
  CB7_B  = M_D_CPU1_SB_CB<7>
  VSS103  = GND
  DQS4_B_C  = M_D_CPU1_SB_DQS_DN<4>
  DQS4_B_T  = M_D_CPU1_SB_DQS_DP<4>
  VSS104  = GND
  CB2_B  = M_D_CPU1_SB_CB<2>
  VSS105  = GND
  CB3_B  = M_D_CPU1_SB_CB<3>
  VSS106  = GND
  DQ2_B  = M_D_CPU1_SB_DQ<2>
  VSS107  = GND
  DQ3_B  = M_D_CPU1_SB_DQ<3>
  VSS108  = GND
  \dqs5_b_c||tdqs5_b_c\  = M_D_CPU1_SB_DQS_DN<5>
  \dqs5_b_t||tdqs5_b_t\  = M_D_CPU1_SB_DQS_DP<5>
  VSS109  = GND
  DQ6_B  = M_D_CPU1_SB_DQ<6>
  VSS110  = GND
  DQ7_B  = M_D_CPU1_SB_DQ<7>
  VSS111  = GND
  DQ10_B  = M_D_CPU1_SB_DQ<10>
  VSS112  = GND
  DQ11_B  = M_D_CPU1_SB_DQ<11>
  VSS113  = GND
  \dqs6_b_c||tdqs6_b_c\  = M_D_CPU1_SB_DQS_DN<6>
  \dqs6_b_t||tdqs6_b_t\  = M_D_CPU1_SB_DQS_DP<6>
  VSS114  = GND
  DQ14_B  = M_D_CPU1_SB_DQ<14>
  VSS115  = GND
  DQ15_B  = M_D_CPU1_SB_DQ<15>
  VSS116  = GND
  DQ18_B  = M_D_CPU1_SB_DQ<18>
  VSS117  = GND
  DQ19_B  = M_D_CPU1_SB_DQ<19>
  VSS118  = GND
  \dqs7_b_c||tdqs7_b_c\  = M_D_CPU1_SB_DQS_DN<7>
  \dqs7_b_t||tdqs7_b_t\  = M_D_CPU1_SB_DQS_DP<7>
  VSS119  = GND
  DQ22_B  = M_D_CPU1_SB_DQ<22>
  VSS120  = GND
  DQ23_B  = M_D_CPU1_SB_DQ<23>
  VSS121  = GND
  DQ26_B  = M_D_CPU1_SB_DQ<26>
  VSS122  = GND
  DQ27_B  = M_D_CPU1_SB_DQ<27>
  VSS123  = GND
  \dqs8_b_c||tdqs8_b_c\  = M_D_CPU1_SB_DQS_DN<8>
  \dqs8_b_t||tdqs8_b_t\  = M_D_CPU1_SB_DQS_DP<8>
  VSS124  = GND
  DQ30_B  = M_D_CPU1_SB_DQ<30>
  VSS125  = GND
  DQ31_B  = M_D_CPU1_SB_DQ<31>
  VSS126  = GND
  G1  = GND
  G2  = GND
  G3  = GND

(kicad_pcb
	(version 20260206)
	(generator "pcbnew")
	(generator_version "10.0")
	(general
		(thickness 1.6)
		(legacy_teardrops no)
	)
	(paper "A4")
	(title_block
		(title "03242023_DA0F0TMBIJ0_F0T_Motherboard_J_brd_V01_OCP.brd")
		(comment 1 "Grand Teton / footprint 3586 of 6105 (J23), pads 138-182 of 291")
	)
	(layers
		(0 "F.Cu" signal "TOP")
		(4 "In1.Cu" signal "GND")
		(6 "In2.Cu" signal "IN1")
		(8 "In3.Cu" signal "GND1")
		(10 "In4.Cu" signal "IN2")
		(12 "In5.Cu" signal "GND2")
		(14 "In6.Cu" signal "IN3")
		(16 "In7.Cu" signal "GND3")
		(18 "In8.Cu" signal "VCC")
		(20 "In9.Cu" signal "VCC1")
		(22 "In10.Cu" signal "GND4")
		(24 "In11.Cu" signal "IN4")
		(26 "In12.Cu" signal "GND5")
		(28 "In13.Cu" signal "IN5")
		(30 "In14.Cu" signal "GND6")
		(32 "In15.Cu" signal "IN6")
		(34 "In16.Cu" signal "GND7")
		(2 "B.Cu" signal "BOTTOM")
		(9 "F.Adhes" user "F.Adhesive")
		(11 "B.Adhes" user "B.Adhesive")
		(13 "F.Paste" user "Package Geometry/Pastemask Top")
		(15 "B.Paste" user "Package Geometry/Pastemask Bottom")
		(5 "F.SilkS" user "Ref Des/Silkscreen Top")
		(7 "B.SilkS" user "Ref Des/Silkscreen Bottom")
		(1 "F.Mask" user "Board Geometry/Soldermask Top")
		(3 "B.Mask" user "Board Geometry/Soldermask Bottom")
		(17 "Dwgs.User" user "User.Drawings")
		(19 "Cmts.User" user "User.Comments")
		(21 "Eco1.User" user "User.Eco1")
		(23 "Eco2.User" user "User.Eco2")
		(25 "Edge.Cuts" user "Board Geometry/Outline")
		(27 "Margin" user)
		(31 "F.CrtYd" user "Package Geometry/Place Bound Top")
		(29 "B.CrtYd" user "Package Geometry/Place Bound Bottom")
		(35 "F.Fab" user "Ref Des/Assembly Top")
		(33 "B.Fab" user "Ref Des/Assembly Bottom")
	)
	(footprint ""
		(layer "F.Cu")
		(at 10.19048 -258.091686)
		(property "Reference" "J23"
			(at -5.69468 -80.480408 0)
			(unlocked yes)
			(layer "F.SilkS")
			(effects
				(font
					(size 0.7874 0.5842)
					(thickness 0.1524)
				)
				(justify left)
			)
		)
		(property "Value" ""
			(at 0 0 0)
			(layer "F.Fab")
			(effects
				(font
					(size 1.27 1.27)
				)
			)
		)
		(duplicate_pad_numbers_are_jumpers no)
		(pad "138" smd rect
			(at -2.050034 58.224928 270)
			(size 0.519938 1.4986)
			(layers "F.Cu" "F.Mask" "F.Paste")
			(net "M_D_CPU1_SB_DQS_DN<3>")
		)
		(pad "139" smd rect
			(at -2.050034 59.075066 270)
			(size 0.519938 1.4986)
			(layers "F.Cu" "F.Mask" "F.Paste")
			(net "GND")
		)
		(pad "140" smd rect
			(at -2.050034 59.92495 270)
			(size 0.519938 1.4986)
			(layers "F.Cu" "F.Mask" "F.Paste")
			(net "M_D_CPU1_SB_DQ<28>")
		)
		(pad "141" smd rect
			(at -2.050034 60.775088 270)
			(size 0.519938 1.4986)
			(layers "F.Cu" "F.Mask" "F.Paste")
			(net "GND")
		)
		(pad "142" smd rect
			(at -2.050034 61.624972 270)
			(size 0.519938 1.4986)
			(layers "F.Cu" "F.Mask" "F.Paste")
			(net "M_D_CPU1_SB_DQ<29>")
		)
		(pad "143" smd rect
			(at -2.050034 62.47511 270)
			(size 0.519938 1.4986)
			(layers "F.Cu" "F.Mask" "F.Paste")
			(net "GND")
		)
		(pad "144" smd rect
			(at -2.050034 63.324994 270)
			(size 0.519938 1.4986)
			(layers "F.Cu" "F.Mask" "F.Paste")
			(net "TP_CHD_CPU1_DIMM1_FRU_1")
		)
		(pad "145" smd rect
			(at 2.050034 -63.324994 270)
			(size 0.519938 1.4986)
			(layers "F.Cu" "F.Mask" "F.Paste")
			(net "P12V_S3_AUX_CPU1_NVDIMM")
		)
		(pad "146" smd rect
			(at 2.050034 -62.47511 270)
			(size 0.519938 1.4986)
			(layers "F.Cu" "F.Mask" "F.Paste")
			(net "P12V_S3_AUX_CPU1_NVDIMM")
		)
		(pad "147" smd rect
			(at 2.050034 -61.624972 270)
			(size 0.519938 1.4986)
			(layers "F.Cu" "F.Mask" "F.Paste")
			(net "PWRGD_CHD_CPU1_DIMM1")
		)
		(pad "148" smd rect
			(at 2.050034 -60.775088 270)
			(size 0.519938 1.4986)
			(layers "F.Cu" "F.Mask" "F.Paste")
			(net "PD_CHD_CPU1_DIMM1_SAA")
		)
		(pad "149" smd rect
			(at 2.050034 -59.92495 270)
			(size 0.519938 1.4986)
			(layers "F.Cu" "F.Mask" "F.Paste")
			(net "TP_CHD_CPU1_DIMM1_FRU_2")
		)
		(pad "150" smd rect
			(at 2.050034 -59.075066 270)
			(size 0.519938 1.4986)
			(layers "F.Cu" "F.Mask" "F.Paste")
			(net "TP_CHD_CPU1_DIMM1_FRU_3")
		)
		(pad "151" smd rect
			(at 2.050034 -58.224928 270)
			(size 0.519938 1.4986)
			(layers "F.Cu" "F.Mask" "F.Paste")
			(net "GND")
		)
		(pad "152" smd rect
			(at 2.050034 -57.375044 270)
			(size 0.519938 1.4986)
			(layers "F.Cu" "F.Mask" "F.Paste")
			(net "M_D_CPU1_SA_DQ<2>")
		)
		(pad "153" smd rect
			(at 2.050034 -56.524906 270)
			(size 0.519938 1.4986)
			(layers "F.Cu" "F.Mask" "F.Paste")
			(net "GND")
		)
		(pad "154" smd rect
			(at 2.050034 -55.675022 270)
			(size 0.519938 1.4986)
			(layers "F.Cu" "F.Mask" "F.Paste")
			(net "M_D_CPU1_SA_DQ<3>")
		)
		(pad "155" smd rect
			(at 2.050034 -54.824884 270)
			(size 0.519938 1.4986)
			(layers "F.Cu" "F.Mask" "F.Paste")
			(net "GND")
		)
		(pad "156" smd rect
			(at 2.050034 -53.975 270)
			(size 0.519938 1.4986)
			(layers "F.Cu" "F.Mask" "F.Paste")
			(net "M_D_CPU1_SA_DQS_DN<5>")
		)
		(pad "157" smd rect
			(at 2.050034 -53.125116 270)
			(size 0.519938 1.4986)
			(layers "F.Cu" "F.Mask" "F.Paste")
			(net "M_D_CPU1_SA_DQS_DP<5>")
		)
		(pad "158" smd rect
			(at 2.050034 -52.274978 270)
			(size 0.519938 1.4986)
			(layers "F.Cu" "F.Mask" "F.Paste")
			(net "GND")
		)
		(pad "159" smd rect
			(at 2.050034 -51.425094 270)
			(size 0.519938 1.4986)
			(layers "F.Cu" "F.Mask" "F.Paste")
			(net "M_D_CPU1_SA_DQ<6>")
		)
		(pad "160" smd rect
			(at 2.050034 -50.574956 270)
			(size 0.519938 1.4986)
			(layers "F.Cu" "F.Mask" "F.Paste")
			(net "GND")
		)
		(pad "161" smd rect
			(at 2.050034 -49.725072 270)
			(size 0.519938 1.4986)
			(layers "F.Cu" "F.Mask" "F.Paste")
			(net "M_D_CPU1_SA_DQ<7>")
		)
		(pad "162" smd rect
			(at 2.050034 -48.874934 270)
			(size 0.519938 1.4986)
			(layers "F.Cu" "F.Mask" "F.Paste")
			(net "GND")
		)
		(pad "163" smd rect
			(at 2.050034 -48.02505 270)
			(size 0.519938 1.4986)
			(layers "F.Cu" "F.Mask" "F.Paste")
			(net "M_D_CPU1_SA_DQ<10>")
		)
		(pad "164" smd rect
			(at 2.050034 -47.174912 270)
			(size 0.519938 1.4986)
			(layers "F.Cu" "F.Mask" "F.Paste")
			(net "GND")
		)
		(pad "165" smd rect
			(at 2.050034 -46.325028 270)
			(size 0.519938 1.4986)
			(layers "F.Cu" "F.Mask" "F.Paste")
			(net "M_D_CPU1_SA_DQ<11>")
		)
		(pad "166" smd rect
			(at 2.050034 -45.47489 270)
			(size 0.519938 1.4986)
			(layers "F.Cu" "F.Mask" "F.Paste")
			(net "GND")
		)
		(pad "167" smd rect
			(at 2.050034 -44.625006 270)
			(size 0.519938 1.4986)
			(layers "F.Cu" "F.Mask" "F.Paste")
			(net "M_D_CPU1_SA_DQS_DN<6>")
		)
		(pad "168" smd rect
			(at 2.050034 -43.775122 270)
			(size 0.519938 1.4986)
			(layers "F.Cu" "F.Mask" "F.Paste")
			(net "M_D_CPU1_SA_DQS_DP<6>")
		)
		(pad "169" smd rect
			(at 2.050034 -42.924984 270)
			(size 0.519938 1.4986)
			(layers "F.Cu" "F.Mask" "F.Paste")
			(net "GND")
		)
		(pad "170" smd rect
			(at 2.050034 -42.0751 270)
			(size 0.519938 1.4986)
			(layers "F.Cu" "F.Mask" "F.Paste")
			(net "M_D_CPU1_SA_DQ<14>")
		)
		(pad "171" smd rect
			(at 2.050034 -41.224962 270)
			(size 0.519938 1.4986)
			(layers "F.Cu" "F.Mask" "F.Paste")
			(net "GND")
		)
		(pad "172" smd rect
			(at 2.050034 -40.375078 270)
			(size 0.519938 1.4986)
			(layers "F.Cu" "F.Mask" "F.Paste")
			(net "M_D_CPU1_SA_DQ<15>")
		)
		(pad "173" smd rect
			(at 2.050034 -39.52494 270)
			(size 0.519938 1.4986)
			(layers "F.Cu" "F.Mask" "F.Paste")
			(net "GND")
		)
		(pad "174" smd rect
			(at 2.050034 -38.675056 270)
			(size 0.519938 1.4986)
			(layers "F.Cu" "F.Mask" "F.Paste")
			(net "M_D_CPU1_SA_DQ<18>")
		)
		(pad "175" smd rect
			(at 2.050034 -37.824918 270)
			(size 0.519938 1.4986)
			(layers "F.Cu" "F.Mask" "F.Paste")
			(net "GND")
		)
		(pad "176" smd rect
			(at 2.050034 -36.975034 270)
			(size 0.519938 1.4986)
			(layers "F.Cu" "F.Mask" "F.Paste")
			(net "M_D_CPU1_SA_DQ<19>")
		)
		(pad "177" smd rect
			(at 2.050034 -36.124896 270)
			(size 0.519938 1.4986)
			(layers "F.Cu" "F.Mask" "F.Paste")
			(net "GND")
		)
		(pad "178" smd rect
			(at 2.050034 -35.275012 270)
			(size 0.519938 1.4986)
			(layers "F.Cu" "F.Mask" "F.Paste")
			(net "M_D_CPU1_SA_DQS_DN<7>")
		)
		(pad "179" smd rect
			(at 2.050034 -34.425128 270)
			(size 0.519938 1.4986)
			(layers "F.Cu" "F.Mask" "F.Paste")
			(net "M_D_CPU1_SA_DQS_DP<7>")
		)
		(pad "180" smd rect
			(at 2.050034 -33.57499 270)
			(size 0.519938 1.4986)
			(layers "F.Cu" "F.Mask" "F.Paste")
			(net "GND")
		)
		(pad "181" smd rect
			(at 2.050034 -32.725106 270)
			(size 0.519938 1.4986)
			(layers "F.Cu" "F.Mask" "F.Paste")
			(net "M_D_CPU1_SA_DQ<22>")
		)
		(pad "182" smd rect
			(at 2.050034 -31.874968 270)
			(size 0.519938 1.4986)
			(layers "F.Cu" "F.Mask" "F.Paste")
			(net "GND")
		)
	)
)
